(kicad_pcb
	(version 20260206)
	(generator "pcbnew")
	(generator_version "10.0")
	(general
		(thickness 1.6)
		(legacy_teardrops no)
	)
	(paper "A4")
	(title_block
		(title "03242023_DA0F0TMBIJ0_F0T_Motherboard_J_brd_V01_OCP.brd")
		(comment 1 "Grand Teton / footprint 3819 of 6105 (J18), pads 113-224 of 291")
	)
	(layers
		(0 "F.Cu" signal "TOP")
		(4 "In1.Cu" signal "GND")
		(6 "In2.Cu" signal "IN1")
		(8 "In3.Cu" signal "GND1")
		(10 "In4.Cu" signal "IN2")
		(12 "In5.Cu" signal "GND2")
		(14 "In6.Cu" signal "IN3")
		(16 "In7.Cu" signal "GND3")
		(18 "In8.Cu" signal "VCC")
		(20 "In9.Cu" signal "VCC1")
		(22 "In10.Cu" signal "GND4")
		(24 "In11.Cu" signal "IN4")
		(26 "In12.Cu" signal "GND5")
		(28 "In13.Cu" signal "IN5")
		(30 "In14.Cu" signal "GND6")
		(32 "In15.Cu" signal "IN6")
		(34 "In16.Cu" signal "GND7")
		(2 "B.Cu" signal "BOTTOM")
		(9 "F.Adhes" user "F.Adhesive")
		(11 "B.Adhes" user "B.Adhesive")
		(13 "F.Paste" user "Package Geometry/Pastemask Top")
		(15 "B.Paste" user "Package Geometry/Pastemask Bottom")
		(5 "F.SilkS" user "Ref Des/Silkscreen Top")
		(7 "B.SilkS" user "Ref Des/Silkscreen Bottom")
		(1 "F.Mask" user "Board Geometry/Soldermask Top")
		(3 "B.Mask" user "Board Geometry/Soldermask Bottom")
		(17 "Dwgs.User" user "User.Drawings")
		(19 "Cmts.User" user "User.Comments")
		(21 "Eco1.User" user "User.Eco1")
		(23 "Eco2.User" user "User.Eco2")
		(25 "Edge.Cuts" user "Board Geometry/Outline")
		(27 "Margin" user)
		(31 "F.CrtYd" user "Package Geometry/Place Bound Top")
		(29 "B.CrtYd" user "Package Geometry/Place Bound Bottom")
		(35 "F.Fab" user "Ref Des/Assembly Top")
		(33 "B.Fab" user "Ref Des/Assembly Bottom")
	)
	(footprint ""
		(layer "F.Cu")
		(at 62.99708 -258.091686)
		(property "Reference" "J18"
			(at -1.547622 -81.836514 0)
			(unlocked yes)
			(layer "F.SilkS")
			(effects
				(font
					(size 0.7874 0.5842)
					(thickness 0.1524)
				)
				(justify left)
			)
		)
		(property "Value" ""
			(at 0 0 0)
			(layer "F.Fab")
			(effects
				(font
					(size 1.27 1.27)
				)
			)
		)
		(duplicate_pad_numbers_are_jumpers no)
		(pad "113" smd rect
			(at -2.050034 36.975034 270)
			(size 0.519938 1.4986)
			(layers "F.Cu" "F.Mask" "F.Paste")
			(net "M_A_CPU1_SB_DQ<9>")
		)
		(pad "114" smd rect
			(at -2.050034 37.824918 270)
			(size 0.519938 1.4986)
			(layers "F.Cu" "F.Mask" "F.Paste")
			(net "GND")
		)
		(pad "115" smd rect
			(at -2.050034 38.675056 270)
			(size 0.519938 1.4986)
			(layers "F.Cu" "F.Mask" "F.Paste")
			(net "M_A_CPU1_SB_DQS_DP<1>")
		)
		(pad "116" smd rect
			(at -2.050034 39.52494 270)
			(size 0.519938 1.4986)
			(layers "F.Cu" "F.Mask" "F.Paste")
			(net "M_A_CPU1_SB_DQS_DN<1>")
		)
		(pad "117" smd rect
			(at -2.050034 40.375078 270)
			(size 0.519938 1.4986)
			(layers "F.Cu" "F.Mask" "F.Paste")
			(net "GND")
		)
		(pad "118" smd rect
			(at -2.050034 41.224962 270)
			(size 0.519938 1.4986)
			(layers "F.Cu" "F.Mask" "F.Paste")
			(net "M_A_CPU1_SB_DQ<12>")
		)
		(pad "119" smd rect
			(at -2.050034 42.0751 270)
			(size 0.519938 1.4986)
			(layers "F.Cu" "F.Mask" "F.Paste")
			(net "GND")
		)
		(pad "120" smd rect
			(at -2.050034 42.924984 270)
			(size 0.519938 1.4986)
			(layers "F.Cu" "F.Mask" "F.Paste")
			(net "M_A_CPU1_SB_DQ<13>")
		)
		(pad "121" smd rect
			(at -2.050034 43.775122 270)
			(size 0.519938 1.4986)
			(layers "F.Cu" "F.Mask" "F.Paste")
			(net "GND")
		)
		(pad "122" smd rect
			(at -2.050034 44.625006 270)
			(size 0.519938 1.4986)
			(layers "F.Cu" "F.Mask" "F.Paste")
			(net "M_A_CPU1_SB_DQ<16>")
		)
		(pad "123" smd rect
			(at -2.050034 45.47489 270)
			(size 0.519938 1.4986)
			(layers "F.Cu" "F.Mask" "F.Paste")
			(net "GND")
		)
		(pad "124" smd rect
			(at -2.050034 46.325028 270)
			(size 0.519938 1.4986)
			(layers "F.Cu" "F.Mask" "F.Paste")
			(net "M_A_CPU1_SB_DQ<17>")
		)
		(pad "125" smd rect
			(at -2.050034 47.174912 270)
			(size 0.519938 1.4986)
			(layers "F.Cu" "F.Mask" "F.Paste")
			(net "GND")
		)
		(pad "126" smd rect
			(at -2.050034 48.02505 270)
			(size 0.519938 1.4986)
			(layers "F.Cu" "F.Mask" "F.Paste")
			(net "M_A_CPU1_SB_DQS_DP<2>")
		)
		(pad "127" smd rect
			(at -2.050034 48.874934 270)
			(size 0.519938 1.4986)
			(layers "F.Cu" "F.Mask" "F.Paste")
			(net "M_A_CPU1_SB_DQS_DN<2>")
		)
		(pad "128" smd rect
			(at -2.050034 49.725072 270)
			(size 0.519938 1.4986)
			(layers "F.Cu" "F.Mask" "F.Paste")
			(net "GND")
		)
		(pad "129" smd rect
			(at -2.050034 50.574956 270)
			(size 0.519938 1.4986)
			(layers "F.Cu" "F.Mask" "F.Paste")
			(net "M_A_CPU1_SB_DQ<20>")
		)
		(pad "130" smd rect
			(at -2.050034 51.425094 270)
			(size 0.519938 1.4986)
			(layers "F.Cu" "F.Mask" "F.Paste")
			(net "GND")
		)
		(pad "131" smd rect
			(at -2.050034 52.274978 270)
			(size 0.519938 1.4986)
			(layers "F.Cu" "F.Mask" "F.Paste")
			(net "M_A_CPU1_SB_DQ<21>")
		)
		(pad "132" smd rect
			(at -2.050034 53.125116 270)
			(size 0.519938 1.4986)
			(layers "F.Cu" "F.Mask" "F.Paste")
			(net "GND")
		)
		(pad "133" smd rect
			(at -2.050034 53.975 270)
			(size 0.519938 1.4986)
			(layers "F.Cu" "F.Mask" "F.Paste")
			(net "M_A_CPU1_SB_DQ<24>")
		)
		(pad "134" smd rect
			(at -2.050034 54.824884 270)
			(size 0.519938 1.4986)
			(layers "F.Cu" "F.Mask" "F.Paste")
			(net "GND")
		)
		(pad "135" smd rect
			(at -2.050034 55.675022 270)
			(size 0.519938 1.4986)
			(layers "F.Cu" "F.Mask" "F.Paste")
			(net "M_A_CPU1_SB_DQ<25>")
		)
		(pad "136" smd rect
			(at -2.050034 56.524906 270)
			(size 0.519938 1.4986)
			(layers "F.Cu" "F.Mask" "F.Paste")
			(net "GND")
		)
		(pad "137" smd rect
			(at -2.050034 57.375044 270)
			(size 0.519938 1.4986)
			(layers "F.Cu" "F.Mask" "F.Paste")
			(net "M_A_CPU1_SB_DQS_DP<3>")
		)
		(pad "138" smd rect
			(at -2.050034 58.224928 270)
			(size 0.519938 1.4986)
			(layers "F.Cu" "F.Mask" "F.Paste")
			(net "M_A_CPU1_SB_DQS_DN<3>")
		)
		(pad "139" smd rect
			(at -2.050034 59.075066 270)
			(size 0.519938 1.4986)
			(layers "F.Cu" "F.Mask" "F.Paste")
			(net "GND")
		)
		(pad "140" smd rect
			(at -2.050034 59.92495 270)
			(size 0.519938 1.4986)
			(layers "F.Cu" "F.Mask" "F.Paste")
			(net "M_A_CPU1_SB_DQ<28>")
		)
		(pad "141" smd rect
			(at -2.050034 60.775088 270)
			(size 0.519938 1.4986)
			(layers "F.Cu" "F.Mask" "F.Paste")
			(net "GND")
		)
		(pad "142" smd rect
			(at -2.050034 61.624972 270)
			(size 0.519938 1.4986)
			(layers "F.Cu" "F.Mask" "F.Paste")
			(net "M_A_CPU1_SB_DQ<29>")
		)
		(pad "143" smd rect
			(at -2.050034 62.47511 270)
			(size 0.519938 1.4986)
			(layers "F.Cu" "F.Mask" "F.Paste")
			(net "GND")
		)
		(pad "144" smd rect
			(at -2.050034 63.324994 270)
			(size 0.519938 1.4986)
			(layers "F.Cu" "F.Mask" "F.Paste")
			(net "TP_CHA_CPU1_DIMM2_FRU_1")
		)
		(pad "145" smd rect
			(at 2.050034 -63.324994 270)
			(size 0.519938 1.4986)
			(layers "F.Cu" "F.Mask" "F.Paste")
			(net "P12V_S3_AUX_CPU1_NVDIMM")
		)
		(pad "146" smd rect
			(at 2.050034 -62.47511 270)
			(size 0.519938 1.4986)
			(layers "F.Cu" "F.Mask" "F.Paste")
			(net "P12V_S3_AUX_CPU1_NVDIMM")
		)
		(pad "147" smd rect
			(at 2.050034 -61.624972 270)
			(size 0.519938 1.4986)
			(layers "F.Cu" "F.Mask" "F.Paste")
			(net "PWRGD_CHA_CPU1_DIMM2")
		)
		(pad "148" smd rect
			(at 2.050034 -60.775088 270)
			(size 0.519938 1.4986)
			(layers "F.Cu" "F.Mask" "F.Paste")
			(net "PD_CHA_CPU1_DIMM2_SAA")
		)
		(pad "149" smd rect
			(at 2.050034 -59.92495 270)
			(size 0.519938 1.4986)
			(layers "F.Cu" "F.Mask" "F.Paste")
			(net "TP_CHA_CPU1_DIMM2_FRU_2")
		)
		(pad "150" smd rect
			(at 2.050034 -59.075066 270)
			(size 0.519938 1.4986)
			(layers "F.Cu" "F.Mask" "F.Paste")
			(net "TP_CHA_CPU1_DIMM2_FRU_3")
		)
		(pad "151" smd rect
			(at 2.050034 -58.224928 270)
			(size 0.519938 1.4986)
			(layers "F.Cu" "F.Mask" "F.Paste")
			(net "GND")
		)
		(pad "152" smd rect
			(at 2.050034 -57.375044 270)
			(size 0.519938 1.4986)
			(layers "F.Cu" "F.Mask" "F.Paste")
			(net "M_A_CPU1_SA_DQ<2>")
		)
		(pad "153" smd rect
			(at 2.050034 -56.524906 270)
			(size 0.519938 1.4986)
			(layers "F.Cu" "F.Mask" "F.Paste")
			(net "GND")
		)
		(pad "154" smd rect
			(at 2.050034 -55.675022 270)
			(size 0.519938 1.4986)
			(layers "F.Cu" "F.Mask" "F.Paste")
			(net "M_A_CPU1_SA_DQ<3>")
		)
		(pad "155" smd rect
			(at 2.050034 -54.824884 270)
			(size 0.519938 1.4986)
			(layers "F.Cu" "F.Mask" "F.Paste")
			(net "GND")
		)
		(pad "156" smd rect
			(at 2.050034 -53.975 270)
			(size 0.519938 1.4986)
			(layers "F.Cu" "F.Mask" "F.Paste")
			(net "M_A_CPU1_SA_DQS_DN<5>")
		)
		(pad "157" smd rect
			(at 2.050034 -53.125116 270)
			(size 0.519938 1.4986)
			(layers "F.Cu" "F.Mask" "F.Paste")
			(net "M_A_CPU1_SA_DQS_DP<5>")
		)
		(pad "158" smd rect
			(at 2.050034 -52.274978 270)
			(size 0.519938 1.4986)
			(layers "F.Cu" "F.Mask" "F.Paste")
			(net "GND")
		)
		(pad "159" smd rect
			(at 2.050034 -51.425094 270)
			(size 0.519938 1.4986)
			(layers "F.Cu" "F.Mask" "F.Paste")
			(net "M_A_CPU1_SA_DQ<6>")
		)
		(pad "160" smd rect
			(at 2.050034 -50.574956 270)
			(size 0.519938 1.4986)
			(layers "F.Cu" "F.Mask" "F.Paste")
			(net "GND")
		)
		(pad "161" smd rect
			(at 2.050034 -49.725072 270)
			(size 0.519938 1.4986)
			(layers "F.Cu" "F.Mask" "F.Paste")
			(net "M_A_CPU1_SA_DQ<7>")
		)
		(pad "162" smd rect
			(at 2.050034 -48.874934 270)
			(size 0.519938 1.4986)
			(layers "F.Cu" "F.Mask" "F.Paste")
			(net "GND")
		)
		(pad "163" smd rect
			(at 2.050034 -48.02505 270)
			(size 0.519938 1.4986)
			(layers "F.Cu" "F.Mask" "F.Paste")
			(net "M_A_CPU1_SA_DQ<10>")
		)
		(pad "164" smd rect
			(at 2.050034 -47.174912 270)
			(size 0.519938 1.4986)
			(layers "F.Cu" "F.Mask" "F.Paste")
			(net "GND")
		)
		(pad "165" smd rect
			(at 2.050034 -46.325028 270)
			(size 0.519938 1.4986)
			(layers "F.Cu" "F.Mask" "F.Paste")
			(net "M_A_CPU1_SA_DQ<11>")
		)
		(pad "166" smd rect
			(at 2.050034 -45.47489 270)
			(size 0.519938 1.4986)
			(layers "F.Cu" "F.Mask" "F.Paste")
			(net "GND")
		)
		(pad "167" smd rect
			(at 2.050034 -44.625006 270)
			(size 0.519938 1.4986)
			(layers "F.Cu" "F.Mask" "F.Paste")
			(net "M_A_CPU1_SA_DQS_DN<6>")
		)
		(pad "168" smd rect
			(at 2.050034 -43.775122 270)
			(size 0.519938 1.4986)
			(layers "F.Cu" "F.Mask" "F.Paste")
			(net "M_A_CPU1_SA_DQS_DP<6>")
		)
		(pad "169" smd rect
			(at 2.050034 -42.924984 270)
			(size 0.519938 1.4986)
			(layers "F.Cu" "F.Mask" "F.Paste")
			(net "GND")
		)
		(pad "170" smd rect
			(at 2.050034 -42.0751 270)
			(size 0.519938 1.4986)
			(layers "F.Cu" "F.Mask" "F.Paste")
			(net "M_A_CPU1_SA_DQ<14>")
		)
		(pad "171" smd rect
			(at 2.050034 -41.224962 270)
			(size 0.519938 1.4986)
			(layers "F.Cu" "F.Mask" "F.Paste")
			(net "GND")
		)
		(pad "172" smd rect
			(at 2.050034 -40.375078 270)
			(size 0.519938 1.4986)
			(layers "F.Cu" "F.Mask" "F.Paste")
			(net "M_A_CPU1_SA_DQ<15>")
		)
		(pad "173" smd rect
			(at 2.050034 -39.52494 270)
			(size 0.519938 1.4986)
			(layers "F.Cu" "F.Mask" "F.Paste")
			(net "GND")
		)
		(pad "174" smd rect
			(at 2.050034 -38.675056 270)
			(size 0.519938 1.4986)
			(layers "F.Cu" "F.Mask" "F.Paste")
			(net "M_A_CPU1_SA_DQ<18>")
		)
		(pad "175" smd rect
			(at 2.050034 -37.824918 270)
			(size 0.519938 1.4986)
			(layers "F.Cu" "F.Mask" "F.Paste")
			(net "GND")
		)
		(pad "176" smd rect
			(at 2.050034 -36.975034 270)
			(size 0.519938 1.4986)
			(layers "F.Cu" "F.Mask" "F.Paste")
			(net "M_A_CPU1_SA_DQ<19>")
		)
		(pad "177" smd rect
			(at 2.050034 -36.124896 270)
			(size 0.519938 1.4986)
			(layers "F.Cu" "F.Mask" "F.Paste")
			(net "GND")
		)
		(pad "178" smd rect
			(at 2.050034 -35.275012 270)
			(size 0.519938 1.4986)
			(layers "F.Cu" "F.Mask" "F.Paste")
			(net "M_A_CPU1_SA_DQS_DN<7>")
		)
		(pad "179" smd rect
			(at 2.050034 -34.425128 270)
			(size 0.519938 1.4986)
			(layers "F.Cu" "F.Mask" "F.Paste")
			(net "M_A_CPU1_SA_DQS_DP<7>")
		)
		(pad "180" smd rect
			(at 2.050034 -33.57499 270)
			(size 0.519938 1.4986)
			(layers "F.Cu" "F.Mask" "F.Paste")
			(net "GND")
		)
		(pad "181" smd rect
			(at 2.050034 -32.725106 270)
			(size 0.519938 1.4986)
			(layers "F.Cu" "F.Mask" "F.Paste")
			(net "M_A_CPU1_SA_DQ<22>")
		)
		(pad "182" smd rect
			(at 2.050034 -31.874968 270)
			(size 0.519938 1.4986)
			(layers "F.Cu" "F.Mask" "F.Paste")
			(net "GND")
		)
		(pad "183" smd rect
			(at 2.050034 -31.025084 270)
			(size 0.519938 1.4986)
			(layers "F.Cu" "F.Mask" "F.Paste")
			(net "M_A_CPU1_SA_DQ<23>")
		)
		(pad "184" smd rect
			(at 2.050034 -30.174946 270)
			(size 0.519938 1.4986)
			(layers "F.Cu" "F.Mask" "F.Paste")
			(net "GND")
		)
		(pad "185" smd rect
			(at 2.050034 -29.325062 270)
			(size 0.519938 1.4986)
			(layers "F.Cu" "F.Mask" "F.Paste")
			(net "M_A_CPU1_SA_DQ<26>")
		)
		(pad "186" smd rect
			(at 2.050034 -28.474924 270)
			(size 0.519938 1.4986)
			(layers "F.Cu" "F.Mask" "F.Paste")
			(net "GND")
		)
		(pad "187" smd rect
			(at 2.050034 -27.62504 270)
			(size 0.519938 1.4986)
			(layers "F.Cu" "F.Mask" "F.Paste")
			(net "M_A_CPU1_SA_DQ<27>")
		)
		(pad "188" smd rect
			(at 2.050034 -26.774902 270)
			(size 0.519938 1.4986)
			(layers "F.Cu" "F.Mask" "F.Paste")
			(net "GND")
		)
		(pad "189" smd rect
			(at 2.050034 -25.925018 270)
			(size 0.519938 1.4986)
			(layers "F.Cu" "F.Mask" "F.Paste")
			(net "M_A_CPU1_SA_DQS_DN<8>")
		)
		(pad "190" smd rect
			(at 2.050034 -25.07488 270)
			(size 0.519938 1.4986)
			(layers "F.Cu" "F.Mask" "F.Paste")
			(net "M_A_CPU1_SA_DQS_DP<8>")
		)
		(pad "191" smd rect
			(at 2.050034 -24.224996 270)
			(size 0.519938 1.4986)
			(layers "F.Cu" "F.Mask" "F.Paste")
			(net "GND")
		)
		(pad "192" smd rect
			(at 2.050034 -23.375112 270)
			(size 0.519938 1.4986)
			(layers "F.Cu" "F.Mask" "F.Paste")
			(net "M_A_CPU1_SA_DQ<30>")
		)
		(pad "193" smd rect
			(at 2.050034 -22.524974 270)
			(size 0.519938 1.4986)
			(layers "F.Cu" "F.Mask" "F.Paste")
			(net "GND")
		)
		(pad "194" smd rect
			(at 2.050034 -21.67509 270)
			(size 0.519938 1.4986)
			(layers "F.Cu" "F.Mask" "F.Paste")
			(net "M_A_CPU1_SA_DQ<31>")
		)
		(pad "195" smd rect
			(at 2.050034 -20.824952 270)
			(size 0.519938 1.4986)
			(layers "F.Cu" "F.Mask" "F.Paste")
			(net "GND")
		)
		(pad "196" smd rect
			(at 2.050034 -19.975068 270)
			(size 0.519938 1.4986)
			(layers "F.Cu" "F.Mask" "F.Paste")
			(net "M_A_CPU1_SA_CB<2>")
		)
		(pad "197" smd rect
			(at 2.050034 -19.12493 270)
			(size 0.519938 1.4986)
			(layers "F.Cu" "F.Mask" "F.Paste")
			(net "GND")
		)
		(pad "198" smd rect
			(at 2.050034 -18.275046 270)
			(size 0.519938 1.4986)
			(layers "F.Cu" "F.Mask" "F.Paste")
			(net "M_A_CPU1_SA_CB<3>")
		)
		(pad "199" smd rect
			(at 2.050034 -17.424908 270)
			(size 0.519938 1.4986)
			(layers "F.Cu" "F.Mask" "F.Paste")
			(net "GND")
		)
		(pad "200" smd rect
			(at 2.050034 -16.575024 270)
			(size 0.519938 1.4986)
			(layers "F.Cu" "F.Mask" "F.Paste")
			(net "M_A_CPU1_SA_DQS_DN<9>")
		)
		(pad "201" smd rect
			(at 2.050034 -15.724886 270)
			(size 0.519938 1.4986)
			(layers "F.Cu" "F.Mask" "F.Paste")
			(net "M_A_CPU1_SA_DQS_DP<9>")
		)
		(pad "202" smd rect
			(at 2.050034 -14.875002 270)
			(size 0.519938 1.4986)
			(layers "F.Cu" "F.Mask" "F.Paste")
			(net "GND")
		)
		(pad "203" smd rect
			(at 2.050034 -14.025118 270)
			(size 0.519938 1.4986)
			(layers "F.Cu" "F.Mask" "F.Paste")
			(net "M_A_CPU1_SA_CB<6>")
		)
		(pad "204" smd rect
			(at 2.050034 -13.17498 270)
			(size 0.519938 1.4986)
			(layers "F.Cu" "F.Mask" "F.Paste")
			(net "GND")
		)
		(pad "205" smd rect
			(at 2.050034 -12.325096 270)
			(size 0.519938 1.4986)
			(layers "F.Cu" "F.Mask" "F.Paste")
			(net "M_A_CPU1_SA_CB<7>")
		)
		(pad "206" smd rect
			(at 2.050034 -11.474958 270)
			(size 0.519938 1.4986)
			(layers "F.Cu" "F.Mask" "F.Paste")
			(net "GND")
		)
		(pad "207" smd rect
			(at 2.050034 -10.625074 270)
			(size 0.519938 1.4986)
			(layers "F.Cu" "F.Mask" "F.Paste")
			(net "RST_M_AB_CPU1_FPGA_N")
		)
		(pad "208" smd rect
			(at 2.050034 -9.774936 270)
			(size 0.519938 1.4986)
			(layers "F.Cu" "F.Mask" "F.Paste")
			(net "GND")
		)
		(pad "209" smd rect
			(at 2.050034 -8.925052 270)
			(size 0.519938 1.4986)
			(layers "F.Cu" "F.Mask" "F.Paste")
			(net "M_A_CPU1_SA_CS_N<3>")
		)
		(pad "210" smd rect
			(at 2.050034 -8.074914 270)
			(size 0.519938 1.4986)
			(layers "F.Cu" "F.Mask" "F.Paste")
			(net "GND")
		)
		(pad "211" smd rect
			(at 2.050034 -7.22503 270)
			(size 0.519938 1.4986)
			(layers "F.Cu" "F.Mask" "F.Paste")
			(net "M_A_CPU1_SA_CA<1>")
		)
		(pad "212" smd rect
			(at 2.050034 -6.374892 270)
			(size 0.519938 1.4986)
			(layers "F.Cu" "F.Mask" "F.Paste")
			(net "GND")
		)
		(pad "213" smd rect
			(at 2.050034 -5.525008 270)
			(size 0.519938 1.4986)
			(layers "F.Cu" "F.Mask" "F.Paste")
			(net "M_A_CPU1_SA_CA<3>")
		)
		(pad "214" smd rect
			(at 2.050034 -4.675124 270)
			(size 0.519938 1.4986)
			(layers "F.Cu" "F.Mask" "F.Paste")
			(net "GND")
		)
		(pad "215" smd rect
			(at 2.050034 -3.824986 270)
			(size 0.519938 1.4986)
			(layers "F.Cu" "F.Mask" "F.Paste")
			(net "M_A_CPU1_SA_CA<5>")
		)
		(pad "216" smd rect
			(at 2.050034 -2.975102 270)
			(size 0.519938 1.4986)
			(layers "F.Cu" "F.Mask" "F.Paste")
			(net "GND")
		)
		(pad "217" smd rect
			(at 2.050034 -2.124964 270)
			(size 0.519938 1.4986)
			(layers "F.Cu" "F.Mask" "F.Paste")
			(net "M_A_CPU1_CLK_DP<1>")
		)
		(pad "218" smd rect
			(at 2.050034 -1.27508 270)
			(size 0.519938 1.4986)
			(layers "F.Cu" "F.Mask" "F.Paste")
			(net "M_A_CPU1_CLK_DN<1>")
		)
		(pad "219" smd rect
			(at 2.050034 -0.424942 270)
			(size 0.519938 1.4986)
			(layers "F.Cu" "F.Mask" "F.Paste")
			(net "GND")
		)
		(pad "220" smd rect
			(at 2.050034 5.525008 270)
			(size 0.519938 1.4986)
			(layers "F.Cu" "F.Mask" "F.Paste")
			(net "TP_CHA_CPU1_DIMM2_FRU_4")
		)
		(pad "221" smd rect
			(at 2.050034 6.374892 270)
			(size 0.519938 1.4986)
			(layers "F.Cu" "F.Mask" "F.Paste")
			(net "M_A_CPU1_SB_CA<1>")
		)
		(pad "222" smd rect
			(at 2.050034 7.22503 270)
			(size 0.519938 1.4986)
			(layers "F.Cu" "F.Mask" "F.Paste")
			(net "GND")
		)
		(pad "223" smd rect
			(at 2.050034 8.074914 270)
			(size 0.519938 1.4986)
			(layers "F.Cu" "F.Mask" "F.Paste")
			(net "M_A_CPU1_SB_CA<3>")
		)
		(pad "224" smd rect
			(at 2.050034 8.925052 270)
			(size 0.519938 1.4986)
			(layers "F.Cu" "F.Mask" "F.Paste")
			(net "GND")
		)
	)
)
